(kicad_pcb
	(version 20221018)
	(generator pcbnew)
	(general
    (thickness 1.586)
  )
	(paper "A4")
	(title_block
    (date "2024-03-26")
    (rev "1.1.3")
		(comment 9 "footprints 101-107 of 146")
	)
	(layers
    (0 "F.Cu" signal)
    (1 "In1.Cu" power)
    (2 "In2.Cu" power)
    (31 "B.Cu" signal)
    (32 "B.Adhes" user "B.Adhesive")
    (33 "F.Adhes" user "F.Adhesive")
    (34 "B.Paste" user)
    (35 "F.Paste" user)
    (36 "B.SilkS" user "B.Silkscreen")
    (37 "F.SilkS" user "F.Silkscreen")
    (38 "B.Mask" user)
    (39 "F.Mask" user)
    (40 "Dwgs.User" user "User.Drawings")
    (41 "Cmts.User" user "User.Comments")
    (42 "Eco1.User" user "User.Eco1")
    (43 "Eco2.User" user "User.Eco2")
    (44 "Edge.Cuts" user)
    (45 "Margin" user)
    (46 "B.CrtYd" user "B.Courtyard")
    (47 "F.CrtYd" user "F.Courtyard")
    (48 "B.Fab" user)
    (49 "F.Fab" user)
  )
	(footprint "scalenode-cm4-baseboard-footprints:C_0402_1005Metric" (layer "B.Cu")
    (at 152.9258 73.7014 -90)
    (descr "Capacitor SMD 0402")
    (tags "capacitor SMD 0402")
    (property "Author" "Antmicro")
    (property "Dielectric" "X5R")
    (property "License" "Apache-2.0")
    (property "MPN" "GRM155R61H104KE14D")
    (property "Manufacturer" "Murata")
    (property "Sheetfile" "interfaces.kicad_sch")
    (property "Sheetname" "Interfaces")
    (property "Val" "100n")
    (property "Voltage" "50V")
    (property "ki_description" " ")
    (attr smd)
    (fp_text reference "C51" (at -3.1514 -0.3492 90) (layer "B.SilkS")
        (effects (font (size 0.7 0.7) (thickness 0.15)) (justify left bottom mirror))
    )
    (fp_text value "C_100n_0402" (at 0 -1.4 90) (layer "B.Fab")
        (effects (font (size 0.7 0.7) (thickness 0.15)) (justify left bottom mirror))
    )
    (fp_text user "License: Apache-2.0" (at -0.932 -5.17 90) (layer "B.Fab") hide
        (effects (font (size 0.7 0.7) (thickness 0.15)) (justify left bottom mirror))
    )
    (fp_text user "${REFERENCE}" (at -0.932 -3.168 90) (layer "B.Fab") hide
        (effects (font (size 0.7 0.7) (thickness 0.15)) (justify left bottom mirror))
    )
    (fp_text user "Author: Antmicro" (at -0.932 -4.17 90) (layer "B.Fab") hide
        (effects (font (size 0.7 0.7) (thickness 0.15)) (justify left bottom mirror))
    )
    (fp_rect (start -0.94 0.47) (end 0.94 -0.47)
      (stroke (width 0.05) (type solid)) (fill none) (layer "B.CrtYd"))
    (fp_rect (start -0.499 0.249) (end 0.499 -0.249)
      (stroke (width 0.15) (type solid)) (fill none) (layer "B.Fab"))
    (pad "1" smd roundrect (at -0.484 0 270) (size 0.59 0.64) (layers "B.Cu" "B.Paste" "B.Mask") (roundrect_rratio 0.25)
      (net 11 "GND") (pintype "passive"))
    (pad "2" smd roundrect (at 0.484 0 270) (size 0.59 0.64) (layers "B.Cu" "B.Paste" "B.Mask") (roundrect_rratio 0.25)
      (net 232 "3V3_RPi") (pintype "passive"))
  )
	(footprint "scalenode-cm4-baseboard-footprints:C_0402_1005Metric" (layer "B.Cu")
    (at 151.9352 73.7014 -90)
    (descr "Capacitor SMD 0402")
    (tags "capacitor SMD 0402")
    (property "Author" "Antmicro")
    (property "Dielectric" "")
    (property "License" "Apache-2.0")
    (property "MPN" "C1005X6S1A105K050BC")
    (property "Manufacturer" "TDK")
    (property "Sheetfile" "interfaces.kicad_sch")
    (property "Sheetname" "Interfaces")
    (property "Val" "1u")
    (property "Voltage" "")
    (property "ki_description" " ")
    (attr smd)
    (fp_text reference "C52" (at -3.2014 -0.3398 90) (layer "B.SilkS")
        (effects (font (size 0.7 0.7) (thickness 0.15)) (justify left bottom mirror))
    )
    (fp_text value "C_1u_0402" (at 0 -1.4 90) (layer "B.Fab")
        (effects (font (size 0.7 0.7) (thickness 0.15)) (justify left bottom mirror))
    )
    (fp_text user "License: Apache-2.0" (at -0.932 -5.17 90) (layer "B.Fab") hide
        (effects (font (size 0.7 0.7) (thickness 0.15)) (justify left bottom mirror))
    )
    (fp_text user "${REFERENCE}" (at -0.932 -3.168 90) (layer "B.Fab") hide
        (effects (font (size 0.7 0.7) (thickness 0.15)) (justify left bottom mirror))
    )
    (fp_text user "Author: Antmicro" (at -0.932 -4.17 90) (layer "B.Fab") hide
        (effects (font (size 0.7 0.7) (thickness 0.15)) (justify left bottom mirror))
    )
    (fp_rect (start -0.94 0.47) (end 0.94 -0.47)
      (stroke (width 0.05) (type solid)) (fill none) (layer "B.CrtYd"))
    (fp_rect (start -0.499 0.249) (end 0.499 -0.249)
      (stroke (width 0.15) (type solid)) (fill none) (layer "B.Fab"))
    (pad "1" smd roundrect (at -0.484 0 270) (size 0.59 0.64) (layers "B.Cu" "B.Paste" "B.Mask") (roundrect_rratio 0.25)
      (net 11 "GND") (pintype "passive"))
    (pad "2" smd roundrect (at 0.484 0 270) (size 0.59 0.64) (layers "B.Cu" "B.Paste" "B.Mask") (roundrect_rratio 0.25)
      (net 232 "3V3_RPi") (pintype "passive"))
  )
	(footprint "scalenode-cm4-baseboard-footprints:MicroSD_Amphenol_1140084168" (layer "B.Cu")
    (at 81.604 85.024 90)
    (property "Author" "Antmicro")
    (property "License" "Apache-2.0")
    (property "MPN" "1140084168")
    (property "Manufacturer" "Amphenol")
    (property "Sheetfile" "interfaces.kicad_sch")
    (property "Sheetname" "Interfaces")
    (property "ki_description" "Micro SD Right Angle, PCB Mount")
    (attr smd)
    (fp_text reference "J4" (at 5.524 7.396 270) (layer "B.SilkS")
        (effects (font (size 0.7 0.7) (thickness 0.15)) (justify left bottom mirror))
    )
    (fp_text value "MicroSD_1140084168" (at 0.894 11.006 270) (layer "B.Fab")
        (effects (font (size 0.7 0.7) (thickness 0.15)) (justify left bottom mirror))
    )
    (fp_text user "${REFERENCE}" (at -6.925 -12.774 270) (layer "B.Fab") hide
        (effects (font (size 0.7 0.7) (thickness 0.15)) (justify left bottom mirror))
    )
    (fp_text user "Author: Antmicro" (at -6.925 -14.1 270) (layer "B.Fab") hide
        (effects (font (size 0.7 0.7) (thickness 0.15)) (justify left bottom mirror))
    )
    (fp_text user "License: Apache-2.0" (at -6.925 -15.4 270) (layer "B.Fab") hide
        (effects (font (size 0.7 0.7) (thickness 0.15)) (justify left bottom mirror))
    )
    (fp_line (start -6.3 1.6) (end -6.3 -4.2)
      (stroke (width 0.15) (type solid)) (layer "B.SilkS"))
    (fp_line (start -6.3 6.1) (end -6.3 4.7)
      (stroke (width 0.15) (type solid)) (layer "B.SilkS"))
    (fp_line (start 4.8 6.1) (end -6.3 6.1)
      (stroke (width 0.15) (type solid)) (layer "B.SilkS"))
    (fp_line (start 6.2 -4.2) (end 6.2 2.2)
      (stroke (width 0.15) (type solid)) (layer "B.SilkS"))
    (fp_line (start 6.2 4) (end 6.2 6.1)
      (stroke (width 0.15) (type solid)) (layer "B.SilkS"))
    (fp_line (start 6.2 6.1) (end 6.1 6.1)
      (stroke (width 0.15) (type solid)) (layer "B.SilkS"))
    (fp_rect (start -6.5 6.3) (end 6.4 -6.2)
      (stroke (width 0.05) (type solid)) (fill none) (layer "B.CrtYd"))
    (fp_line (start -5.6 -5.8) (end -5.6 -9.5)
      (stroke (width 0.12) (type solid)) (layer "B.Fab"))
    (fp_line (start -5.1 -9.1) (end -5.6 -9.2)
      (stroke (width 0.12) (type solid)) (layer "B.Fab"))
    (fp_line (start -5.1 -8.8) (end -5.6 -8.9)
      (stroke (width 0.12) (type solid)) (layer "B.Fab"))
    (fp_line (start -3.8 -8.8) (end -5.1 -9.1)
      (stroke (width 0.12) (type solid)) (layer "B.Fab"))
    (fp_line (start -3.8 -8.5) (end -5.1 -8.8)
      (stroke (width 0.12) (type solid)) (layer "B.Fab"))
    (fp_line (start -2.3 -8.6) (end -3.8 -8.8)
      (stroke (width 0.12) (type solid)) (layer "B.Fab"))
    (fp_line (start -2.3 -8.3) (end -3.8 -8.5)
      (stroke (width 0.12) (type solid)) (layer "B.Fab"))
    (fp_line (start -1 -8.5) (end -2.3 -8.6)
      (stroke (width 0.12) (type solid)) (layer "B.Fab"))
    (fp_line (start -1 -8.2) (end -2.3 -8.3)
      (stroke (width 0.12) (type solid)) (layer "B.Fab"))
    (fp_line (start 0.8 -8.5) (end -1 -8.5)
      (stroke (width 0.12) (type solid)) (layer "B.Fab"))
    (fp_line (start 0.8 -8.2) (end -1 -8.2)
      (stroke (width 0.12) (type solid)) (layer "B.Fab"))
    (fp_line (start 2.1 -8.6) (end 0.8 -8.5)
      (stroke (width 0.12) (type solid)) (layer "B.Fab"))
    (fp_line (start 2.1 -8.3) (end 0.8 -8.2)
      (stroke (width 0.12) (type solid)) (layer "B.Fab"))
    (fp_line (start 2.9 -8.7) (end 2.1 -8.6)
      (stroke (width 0.12) (type solid)) (layer "B.Fab"))
    (fp_line (start 2.9 -8.4) (end 2.1 -8.3)
      (stroke (width 0.12) (type solid)) (layer "B.Fab"))
    (fp_line (start 4.6 -9) (end 2.9 -8.7)
      (stroke (width 0.12) (type solid)) (layer "B.Fab"))
    (fp_line (start 4.6 -8.7) (end 2.9 -8.4)
      (stroke (width 0.12) (type solid)) (layer "B.Fab"))
    (fp_line (start 4.9 -10) (end -5.1 -10)
      (stroke (width 0.12) (type solid)) (layer "B.Fab"))
    (fp_line (start 5.4 -9.5) (end 5.4 -5.8)
      (stroke (width 0.12) (type solid)) (layer "B.Fab"))
    (fp_line (start 5.4 -9.2) (end 4.6 -9)
      (stroke (width 0.12) (type solid)) (layer "B.Fab"))
    (fp_line (start 5.4 -8.9) (end 4.6 -8.7)
      (stroke (width 0.12) (type solid)) (layer "B.Fab"))
    (fp_rect (start -6 5.8) (end 5.999 -5.799)
      (stroke (width 0.1) (type solid)) (fill none) (layer "B.Fab"))
    (fp_arc (start -5.6 -9.5) (mid -5.453553 -9.853553) (end -5.1 -10)
      (stroke (width 0.12) (type solid)) (layer "B.Fab"))
    (fp_arc (start 4.9 -10) (mid 5.253553 -9.853553) (end 5.4 -9.5)
      (stroke (width 0.12) (type solid)) (layer "B.Fab"))
    (pad "1" smd rect (at 3.124 -5.254 270) (size 0.7 1.75) (layers "B.Cu" "B.Paste" "B.Mask")
      (net 33 "SD_DAT2") (pinfunction "DAT2") (pintype "bidirectional"))
    (pad "2" smd rect (at 2.024 -5.254 270) (size 0.7 1.75) (layers "B.Cu" "B.Paste" "B.Mask")
      (net 32 "SD_DAT3") (pinfunction "CD/DAT3") (pintype "bidirectional"))
    (pad "3" smd rect (at 0.925 -5.254 270) (size 0.7 1.75) (layers "B.Cu" "B.Paste" "B.Mask")
      (net 31 "SD_CMD") (pinfunction "CMD") (pintype "bidirectional"))
    (pad "4" smd rect (at -0.176 -5.254 270) (size 0.7 1.75) (layers "B.Cu" "B.Paste" "B.Mask")
      (net 232 "3V3_RPi") (pinfunction "VDD") (pintype "power_in"))
    (pad "5" smd rect (at -1.276 -5.254 270) (size 0.7 1.75) (layers "B.Cu" "B.Paste" "B.Mask")
      (net 30 "SD_CLK") (pinfunction "CLK") (pintype "output"))
    (pad "6" smd rect (at -2.375 -5.254 270) (size 0.7 1.75) (layers "B.Cu" "B.Paste" "B.Mask")
      (net 11 "GND") (pinfunction "VSS") (pintype "power_in"))
    (pad "7" smd rect (at -3.476 -5.254 270) (size 0.7 1.75) (layers "B.Cu" "B.Paste" "B.Mask")
      (net 29 "SD_DAT0") (pinfunction "DAT0") (pintype "bidirectional"))
    (pad "8" smd rect (at -4.576 -5.254 270) (size 0.7 1.75) (layers "B.Cu" "B.Paste" "B.Mask")
      (net 28 "SD_DAT1") (pinfunction "DAT1") (pintype "bidirectional"))
    (pad "9" smd rect (at -5.675 4.05 90) (size 1.4 1) (layers "B.Cu" "B.Paste" "B.Mask")
      (net 201 "Net-(J4-CD1)") (pinfunction "CD1") (pintype "passive"))
    (pad "10" smd rect (at 5.424 5.531) (size 1.4 1) (layers "B.Cu" "B.Paste" "B.Mask")
      (net 11 "GND") (pinfunction "CD2") (pintype "passive"))
    (pad "SH" smd rect (at -5.976 2.48) (size 1.5 0.8) (layers "B.Cu" "B.Paste" "B.Mask")
      (net 11 "GND") (pinfunction "Shell") (pintype "passive"))
    (pad "SH" smd rect (at -5.776 -5.129 90) (size 1.3 1.5) (layers "B.Cu" "B.Paste" "B.Mask")
      (net 11 "GND") (pinfunction "Shell") (pintype "passive"))
    (pad "SH" smd rect (at 5.575 -5.129 90) (size 1.5 1.5) (layers "B.Cu" "B.Paste" "B.Mask")
      (net 11 "GND") (pinfunction "Shell") (pintype "passive"))
    (pad "SH" smd rect (at 5.874 3.13) (size 1.5 0.8) (layers "B.Cu" "B.Paste" "B.Mask")
      (net 11 "GND") (pinfunction "Shell") (pintype "passive"))
  )
	(footprint "scalenode-cm4-baseboard-footprints:R_1206_3216Metric" (layer "B.Cu")
    (at 103.818 59.13)
    (property "Author" "Antmicro")
    (property "Current" "2A")
    (property "DNP" "DNP")
    (property "License" "Apache-2.0")
    (property "MPN" "MCMR12X000_PTL")
    (property "Manufacturer" "Multicomp Pro")
    (property "Sheetfile" "poe.kicad_sch")
    (property "Sheetname" "PoE")
    (property "Tolerance" "~")
    (property "Val" "0R")
    (property "dnp" "")
    (property "exclude_from_bom" "")
    (property "ki_description" "0R resistor in 1206 package with unspecified tolerance")
    (attr exclude_from_pos_files exclude_from_bom)
    (fp_text reference "R17" (at 0.982 -1.38 180) (layer "B.SilkS")
        (effects (font (size 0.7 0.7) (thickness 0.15)) (justify left bottom mirror))
    )
    (fp_text value "R_0R_1206" (at 1.257 1.87 180) (layer "B.Fab")
        (effects (font (size 0.7 0.7) (thickness 0.15)) (justify left bottom mirror))
    )
    (fp_text user "License: Apache-2.0" (at -2.401 -6.3 180) (layer "B.Fab") hide
        (effects (font (size 0.7 0.7) (thickness 0.15)) (justify left bottom mirror))
    )
    (fp_text user "Author: Antmicro" (at -2.401 -4.899 180) (layer "B.Fab") hide
        (effects (font (size 0.7 0.7) (thickness 0.15)) (justify left bottom mirror))
    )
    (fp_text user "${REFERENCE}" (at -2.401 -3.5 180) (layer "B.Fab") hide
        (effects (font (size 0.7 0.7) (thickness 0.15)) (justify left bottom mirror))
    )
    (fp_line (start 0 -0.9) (end -0.5 -0.9)
      (stroke (width 0.15) (type solid)) (layer "B.SilkS"))
    (fp_line (start 0 -0.9) (end 0.498 -0.9)
      (stroke (width 0.15) (type solid)) (layer "B.SilkS"))
    (fp_line (start 0 0.902) (end -0.5 0.902)
      (stroke (width 0.15) (type solid)) (layer "B.SilkS"))
    (fp_line (start 0 0.902) (end 0.498 0.902)
      (stroke (width 0.15) (type solid)) (layer "B.SilkS"))
    (fp_rect (start -2.25 1.05) (end 2.25 -1.05)
      (stroke (width 0.05) (type solid)) (fill none) (layer "B.CrtYd"))
    (fp_line (start -1.601 -0.8) (end 1.6 -0.8)
      (stroke (width 0.15) (type solid)) (layer "B.Fab"))
    (fp_line (start -1.601 0.802) (end -1.601 -0.8)
      (stroke (width 0.15) (type solid)) (layer "B.Fab"))
    (fp_line (start -1.601 0.802) (end 1.6 0.802)
      (stroke (width 0.15) (type solid)) (layer "B.Fab"))
    (fp_line (start 1.6 0.802) (end 1.6 -0.8)
      (stroke (width 0.15) (type solid)) (layer "B.Fab"))
    (pad "1" smd roundrect (at -1.5 0) (size 1.2 1.8) (layers "B.Cu" "B.Paste" "B.Mask") (roundrect_rratio 0.15)
      (net 230 "Earth") (pintype "passive"))
    (pad "2" smd roundrect (at 1.499 0) (size 1.2 1.8) (layers "B.Cu" "B.Paste" "B.Mask") (roundrect_rratio 0.15)
      (net 11 "GND") (pintype "passive"))
  )
	(footprint "scalenode-cm4-baseboard-footprints:R_0402_1005Metric" (layer "B.Cu")
    (at 109.387 62.638 -90)
    (descr "Resistor SMD 0402")
    (tags "resistor SMD 0402")
    (property "Author" "Antmicro")
    (property "License" "Apache-2.0")
    (property "MPN" "CR0402-FX-75R0GLF")
    (property "Manufacturer" "Bourns")
    (property "Sheetfile" "poe.kicad_sch")
    (property "Sheetname" "PoE")
    (property "Tolerance" "1%")
    (property "Val" "75R")
    (property "ki_description" "75R resistor in 0402 package with 1% tolerance")
    (attr smd)
    (fp_text reference "R30" (at -1.088 -1.488 90) (layer "B.SilkS")
        (effects (font (size 0.7 0.7) (thickness 0.15)) (justify left bottom mirror))
    )
    (fp_text value "R_75R_0402" (at 0 -1.4 90) (layer "B.Fab")
        (effects (font (size 0.7 0.7) (thickness 0.15)) (justify left bottom mirror))
    )
    (fp_text user "Author: Antmicro" (at -0.95 -4.169 90) (layer "B.Fab") hide
        (effects (font (size 0.7 0.7) (thickness 0.15)) (justify left bottom mirror))
    )
    (fp_text user "${REFERENCE}" (at -0.95 -3.168 90) (layer "B.Fab") hide
        (effects (font (size 0.7 0.7) (thickness 0.15)) (justify left bottom mirror))
    )
    (fp_text user "License: Apache-2.0" (at -0.95 -5.169 90) (layer "B.Fab") hide
        (effects (font (size 0.7 0.7) (thickness 0.15)) (justify left bottom mirror))
    )
    (fp_rect (start -0.95 0.48) (end 0.95 -0.48)
      (stroke (width 0.05) (type solid)) (fill none) (layer "B.CrtYd"))
    (fp_rect (start -0.5 0.25) (end 0.5 -0.25)
      (stroke (width 0.15) (type solid)) (fill none) (layer "B.Fab"))
    (pad "1" smd roundrect (at -0.485 0 270) (size 0.59 0.64) (layers "B.Cu" "B.Paste" "B.Mask") (roundrect_rratio 0.25)
      (net 175 "Net-(C25-Pad2)") (pintype "passive"))
    (pad "2" smd roundrect (at 0.485 0 270) (size 0.59 0.64) (layers "B.Cu" "B.Paste" "B.Mask") (roundrect_rratio 0.25)
      (net 228 "Net-(L3-TCT4)") (pintype "passive"))
  )
	(footprint "scalenode-cm4-baseboard-footprints:C_1210_3225Metric" (layer "B.Cu")
    (at 109.406 59.511 180)
    (descr "Capacitor SMD 1210")
    (tags "capacitor SMD 1210")
    (property "Author" "Antmicro")
    (property "Dielectric" "")
    (property "License" "Apache-2.0")
    (property "MPN" "C1210C102KGRACTU")
    (property "Manufacturer" "KEMET")
    (property "Sheetfile" "poe.kicad_sch")
    (property "Sheetname" "PoE")
    (property "Val" "1n")
    (property "Voltage" "2kV")
    (property "ki_description" " ")
    (attr smd)
    (fp_text reference "C25" (at -0.969 1.761) (layer "B.SilkS")
        (effects (font (size 0.7 0.7) (thickness 0.15)) (justify left bottom mirror))
    )
    (fp_text value "C_1n_1210_2kV" (at 0 -2.749) (layer "B.Fab")
        (effects (font (size 0.7 0.7) (thickness 0.15)) (justify left bottom mirror))
    )
    (fp_text user "License: Apache-2.0" (at -2.1 -6.749) (layer "B.Fab") hide
        (effects (font (size 0.7 0.7) (thickness 0.15)) (justify left bottom mirror))
    )
    (fp_text user "Author: Antmicro" (at -2.1 -5.749) (layer "B.Fab") hide
        (effects (font (size 0.7 0.7) (thickness 0.15)) (justify left bottom mirror))
    )
    (fp_text user "${REFERENCE}" (at -2.1 -4.749) (layer "B.Fab") hide
        (effects (font (size 0.7 0.7) (thickness 0.15)) (justify left bottom mirror))
    )
    (fp_line (start -0.3 -1.39) (end 0.3 -1.39)
      (stroke (width 0.15) (type solid)) (layer "B.SilkS"))
    (fp_line (start -0.3 1.39) (end 0.3 1.39)
      (stroke (width 0.15) (type solid)) (layer "B.SilkS"))
    (fp_rect (start -2.1 1.75) (end 2.1 -1.75)
      (stroke (width 0.05) (type solid)) (fill none) (layer "B.CrtYd"))
    (fp_rect (start -1.6 1.25) (end 1.6 -1.25)
      (stroke (width 0.15) (type solid)) (fill none) (layer "B.Fab"))
    (pad "1" smd rect (at -1.145 0 180) (size 1.52 3.05) (layers "B.Cu" "B.Paste" "B.Mask")
      (net 11 "GND") (pintype "passive"))
    (pad "2" smd rect (at 1.145 0 180) (size 1.52 3.05) (layers "B.Cu" "B.Paste" "B.Mask")
      (net 175 "Net-(C25-Pad2)") (pintype "passive"))
  )
	(footprint "scalenode-cm4-baseboard-footprints:R_0402_1005Metric" (layer "B.Cu")
    (at 154.4828 73.6346 -90)
    (descr "Resistor SMD 0402")
    (tags "resistor SMD 0402")
    (property "Author" "Antmicro")
    (property "License" "Apache-2.0")
    (property "MPN" "CR0402-FX-1002GLF")
    (property "Manufacturer" "Bourns")
    (property "Sheetfile" "interfaces.kicad_sch")
    (property "Sheetname" "Interfaces")
    (property "Tolerance" "1%")
    (property "Val" "10k")
    (property "ki_description" "10k resistor in 0402 package with 1% tolerance")
    (attr smd)
    (fp_text reference "R55" (at 0.9654 -0.4422 90) (layer "B.SilkS")
        (effects (font (size 0.7 0.7) (thickness 0.15)) (justify left bottom mirror))
    )
    (fp_text value "R_10k_0402" (at 0 -1.4 90) (layer "B.Fab")
        (effects (font (size 0.7 0.7) (thickness 0.15)) (justify left bottom mirror))
    )
    (fp_text user "Author: Antmicro" (at -0.95 -4.169 90) (layer "B.Fab") hide
        (effects (font (size 0.7 0.7) (thickness 0.15)) (justify left bottom mirror))
    )
    (fp_text user "License: Apache-2.0" (at -0.95 -5.169 90) (layer "B.Fab") hide
        (effects (font (size 0.7 0.7) (thickness 0.15)) (justify left bottom mirror))
    )
    (fp_text user "${REFERENCE}" (at -0.95 -3.168 90) (layer "B.Fab") hide
        (effects (font (size 0.7 0.7) (thickness 0.15)) (justify left bottom mirror))
    )
    (fp_rect (start -0.95 0.48) (end 0.95 -0.48)
      (stroke (width 0.05) (type solid)) (fill none) (layer "B.CrtYd"))
    (fp_rect (start -0.5 0.25) (end 0.5 -0.25)
      (stroke (width 0.15) (type solid)) (fill none) (layer "B.Fab"))
    (pad "1" smd roundrect (at -0.485 0 270) (size 0.59 0.64) (layers "B.Cu" "B.Paste" "B.Mask") (roundrect_rratio 0.25)
      (net 264 "Net-(U5-~{OE})") (pintype "passive"))
    (pad "2" smd roundrect (at 0.485 0 270) (size 0.59 0.64) (layers "B.Cu" "B.Paste" "B.Mask") (roundrect_rratio 0.25)
      (net 11 "GND") (pintype "passive"))
  )
)
